(kicad_pcb
	(version 20260206)
	(generator "pcbnew")
	(generator_version "10.0")
	(general
		(thickness 1.6)
		(legacy_teardrops no)
	)
	(paper "A4")
	(title_block
		(title "04192023_DAF0TMB3IC0_F0TG_MB_C_brd_V02_OCP.brd")
		(comment 1 "Grand Teton / footprints 4871-4877 of 8354")
	)
	(layers
		(0 "F.Cu" signal "TOP")
		(4 "In1.Cu" signal "GND")
		(6 "In2.Cu" signal "IN1")
		(8 "In3.Cu" signal "GND1")
		(10 "In4.Cu" signal "IN2")
		(12 "In5.Cu" signal "GND2")
		(14 "In6.Cu" signal "IN3")
		(16 "In7.Cu" signal "GND3")
		(18 "In8.Cu" signal "VCC")
		(20 "In9.Cu" signal "VCC1")
		(22 "In10.Cu" signal "GND4")
		(24 "In11.Cu" signal "IN4")
		(26 "In12.Cu" signal "GND5")
		(28 "In13.Cu" signal "IN5")
		(30 "In14.Cu" signal "GND6")
		(32 "In15.Cu" signal "IN6")
		(34 "In16.Cu" signal "GND7")
		(2 "B.Cu" signal "BOTTOM")
		(9 "F.Adhes" user "F.Adhesive")
		(11 "B.Adhes" user "B.Adhesive")
		(13 "F.Paste" user "Package Geometry/Pastemask Top")
		(15 "B.Paste" user "Package Geometry/Pastemask Bottom")
		(5 "F.SilkS" user "Ref Des/Silkscreen Top")
		(7 "B.SilkS" user "Ref Des/Silkscreen Bottom")
		(1 "F.Mask" user "Board Geometry/Soldermask Top")
		(3 "B.Mask" user "Board Geometry/Soldermask Bottom")
		(17 "Dwgs.User" user "User.Drawings")
		(19 "Cmts.User" user "User.Comments")
		(21 "Eco1.User" user "User.Eco1")
		(23 "Eco2.User" user "User.Eco2")
		(25 "Edge.Cuts" user "Board Geometry/Outline")
		(27 "Margin" user)
		(31 "F.CrtYd" user "Package Geometry/Place Bound Top")
		(29 "B.CrtYd" user "Package Geometry/Place Bound Bottom")
		(35 "F.Fab" user "Ref Des/Assembly Top")
		(33 "B.Fab" user "Ref Des/Assembly Bottom")
	)
	(footprint ""
		(layer "F.Cu")
		(at 422.129712 -57.447688 -90)
		(property "Reference" "R733"
			(at 0 0 270)
			(layer "F.SilkS")
			(hide yes)
			(effects
				(font
					(size 1.27 1.27)
				)
			)
		)
		(property "Value" ""
			(at 0 0 270)
			(layer "F.Fab")
			(effects
				(font
					(size 1.27 1.27)
				)
			)
		)
		(duplicate_pad_numbers_are_jumpers no)
		(fp_line
			(start -0.7874 0.4064)
			(end -0.7874 -0.4064)
			(stroke
				(width 0.1524)
				(type default)
			)
			(layer "F.SilkS")
		)
		(fp_line
			(start 0.7874 0.4064)
			(end -0.7874 0.4064)
			(stroke
				(width 0.1524)
				(type default)
			)
			(layer "F.SilkS")
		)
		(fp_line
			(start -0.7874 -0.4064)
			(end 0.7874 -0.4064)
			(stroke
				(width 0.1524)
				(type default)
			)
			(layer "F.SilkS")
		)
		(fp_line
			(start 0.7874 -0.4064)
			(end 0.7874 0.4064)
			(stroke
				(width 0.1524)
				(type default)
			)
			(layer "F.SilkS")
		)
		(fp_line
			(start -0.67945 0.3048)
			(end -0.67945 -0.305054)
			(stroke
				(width 0.1)
				(type default)
			)
			(layer "F.Fab")
		)
		(fp_line
			(start -0.12065 0.3048)
			(end -0.67945 0.3048)
			(stroke
				(width 0.1)
				(type default)
			)
			(layer "F.Fab")
		)
		(fp_line
			(start 0.120396 0.3048)
			(end 0.120396 0.2794)
			(stroke
				(width 0.1)
				(type default)
			)
			(layer "F.Fab")
		)
		(fp_line
			(start 0.67945 0.3048)
			(end 0.120396 0.3048)
			(stroke
				(width 0.1)
				(type default)
			)
			(layer "F.Fab")
		)
		(fp_line
			(start -0.12065 0.2794)
			(end -0.12065 0.3048)
			(stroke
				(width 0.1)
				(type default)
			)
			(layer "F.Fab")
		)
		(fp_line
			(start 0.120396 0.2794)
			(end -0.12065 0.2794)
			(stroke
				(width 0.1)
				(type default)
			)
			(layer "F.Fab")
		)
		(fp_line
			(start -0.12065 -0.2794)
			(end 0.12065 -0.2794)
			(stroke
				(width 0.1)
				(type default)
			)
			(layer "F.Fab")
		)
		(fp_line
			(start 0.12065 -0.2794)
			(end 0.12065 -0.3048)
			(stroke
				(width 0.1)
				(type default)
			)
			(layer "F.Fab")
		)
		(fp_line
			(start 0.12065 -0.3048)
			(end 0.67945 -0.3048)
			(stroke
				(width 0.1)
				(type default)
			)
			(layer "F.Fab")
		)
		(fp_line
			(start 0.67945 -0.3048)
			(end 0.67945 0.3048)
			(stroke
				(width 0.1)
				(type default)
			)
			(layer "F.Fab")
		)
		(fp_line
			(start -0.67945 -0.305054)
			(end -0.12065 -0.305054)
			(stroke
				(width 0.1)
				(type default)
			)
			(layer "F.Fab")
		)
		(fp_line
			(start -0.12065 -0.305054)
			(end -0.12065 -0.2794)
			(stroke
				(width 0.1)
				(type default)
			)
			(layer "F.Fab")
		)
		(pad "1" smd circle
			(at -0.40005 0 270)
			(size 0 0)
			(layers "F.Cu" "F.Mask" "F.Paste")
			(net "P1V8_AUX")
		)
		(pad "2" smd circle
			(at 0.40005 0 270)
			(size 0 0)
			(layers "F.Cu" "F.Mask" "F.Paste")
			(net "FM_JTAG_BMC_R_OE")
		)
	)
	(footprint ""
		(layer "F.Cu")
		(at 115.010946 -52.48148 180)
		(property "Reference" "R6295"
			(at 0 0 180)
			(layer "F.SilkS")
			(hide yes)
			(effects
				(font
					(size 1.27 1.27)
				)
			)
		)
		(property "Value" ""
			(at 0 0 180)
			(layer "F.Fab")
			(effects
				(font
					(size 1.27 1.27)
				)
			)
		)
		(duplicate_pad_numbers_are_jumpers no)
		(fp_line
			(start 0.7874 0.4064)
			(end -0.7874 0.4064)
			(stroke
				(width 0.1524)
				(type default)
			)
			(layer "F.SilkS")
		)
		(fp_line
			(start 0.7874 -0.4064)
			(end 0.7874 0.4064)
			(stroke
				(width 0.1524)
				(type default)
			)
			(layer "F.SilkS")
		)
		(fp_line
			(start -0.7874 0.4064)
			(end -0.7874 -0.4064)
			(stroke
				(width 0.1524)
				(type default)
			)
			(layer "F.SilkS")
		)
		(fp_line
			(start -0.7874 -0.4064)
			(end 0.7874 -0.4064)
			(stroke
				(width 0.1524)
				(type default)
			)
			(layer "F.SilkS")
		)
		(fp_line
			(start 0.67945 0.3048)
			(end 0.120396 0.3048)
			(stroke
				(width 0.1)
				(type default)
			)
			(layer "F.Fab")
		)
		(fp_line
			(start 0.67945 -0.3048)
			(end 0.67945 0.3048)
			(stroke
				(width 0.1)
				(type default)
			)
			(layer "F.Fab")
		)
		(fp_line
			(start 0.12065 -0.2794)
			(end 0.12065 -0.3048)
			(stroke
				(width 0.1)
				(type default)
			)
			(layer "F.Fab")
		)
		(fp_line
			(start 0.12065 -0.3048)
			(end 0.67945 -0.3048)
			(stroke
				(width 0.1)
				(type default)
			)
			(layer "F.Fab")
		)
		(fp_line
			(start 0.120396 0.3048)
			(end 0.120396 0.2794)
			(stroke
				(width 0.1)
				(type default)
			)
			(layer "F.Fab")
		)
		(fp_line
			(start 0.120396 0.2794)
			(end -0.12065 0.2794)
			(stroke
				(width 0.1)
				(type default)
			)
			(layer "F.Fab")
		)
		(fp_line
			(start -0.12065 0.3048)
			(end -0.67945 0.3048)
			(stroke
				(width 0.1)
				(type default)
			)
			(layer "F.Fab")
		)
		(fp_line
			(start -0.12065 0.2794)
			(end -0.12065 0.3048)
			(stroke
				(width 0.1)
				(type default)
			)
			(layer "F.Fab")
		)
		(fp_line
			(start -0.12065 -0.2794)
			(end 0.12065 -0.2794)
			(stroke
				(width 0.1)
				(type default)
			)
			(layer "F.Fab")
		)
		(fp_line
			(start -0.12065 -0.305054)
			(end -0.12065 -0.2794)
			(stroke
				(width 0.1)
				(type default)
			)
			(layer "F.Fab")
		)
		(fp_line
			(start -0.67945 0.3048)
			(end -0.67945 -0.305054)
			(stroke
				(width 0.1)
				(type default)
			)
			(layer "F.Fab")
		)
		(fp_line
			(start -0.67945 -0.305054)
			(end -0.12065 -0.305054)
			(stroke
				(width 0.1)
				(type default)
			)
			(layer "F.Fab")
		)
		(pad "1" smd circle
			(at -0.40005 0 180)
			(size 0 0)
			(layers "F.Cu" "F.Mask" "F.Paste")
			(net "USB_HUB2_TI_OVERCCUR4")
		)
		(pad "2" smd circle
			(at 0.40005 0 180)
			(size 0 0)
			(layers "F.Cu" "F.Mask" "F.Paste")
			(net "USB_HUB2_TI_OVERCUR4_MRP_I2C_SLV_CFG1")
		)
	)
	(footprint ""
		(layer "F.Cu")
		(at 250.465336 -75.092814)
		(property "Reference" "R3775"
			(at 0 0 0)
			(layer "F.SilkS")
			(hide yes)
			(effects
				(font
					(size 1.27 1.27)
				)
			)
		)
		(property "Value" ""
			(at 0 0 0)
			(layer "F.Fab")
			(effects
				(font
					(size 1.27 1.27)
				)
			)
		)
		(duplicate_pad_numbers_are_jumpers no)
		(fp_line
			(start -0.7874 -0.4064)
			(end 0.7874 -0.4064)
			(stroke
				(width 0.1524)
				(type default)
			)
			(layer "F.SilkS")
		)
		(fp_line
			(start -0.7874 0.4064)
			(end -0.7874 -0.4064)
			(stroke
				(width 0.1524)
				(type default)
			)
			(layer "F.SilkS")
		)
		(fp_line
			(start 0.7874 -0.4064)
			(end 0.7874 0.4064)
			(stroke
				(width 0.1524)
				(type default)
			)
			(layer "F.SilkS")
		)
		(fp_line
			(start 0.7874 0.4064)
			(end -0.7874 0.4064)
			(stroke
				(width 0.1524)
				(type default)
			)
			(layer "F.SilkS")
		)
		(fp_line
			(start -0.67945 -0.305054)
			(end -0.12065 -0.305054)
			(stroke
				(width 0.1)
				(type default)
			)
			(layer "F.Fab")
		)
		(fp_line
			(start -0.67945 0.3048)
			(end -0.67945 -0.305054)
			(stroke
				(width 0.1)
				(type default)
			)
			(layer "F.Fab")
		)
		(fp_line
			(start -0.12065 -0.305054)
			(end -0.12065 -0.2794)
			(stroke
				(width 0.1)
				(type default)
			)
			(layer "F.Fab")
		)
		(fp_line
			(start -0.12065 -0.2794)
			(end 0.12065 -0.2794)
			(stroke
				(width 0.1)
				(type default)
			)
			(layer "F.Fab")
		)
		(fp_line
			(start -0.12065 0.2794)
			(end -0.12065 0.3048)
			(stroke
				(width 0.1)
				(type default)
			)
			(layer "F.Fab")
		)
		(fp_line
			(start -0.12065 0.3048)
			(end -0.67945 0.3048)
			(stroke
				(width 0.1)
				(type default)
			)
			(layer "F.Fab")
		)
		(fp_line
			(start 0.120396 0.2794)
			(end -0.12065 0.2794)
			(stroke
				(width 0.1)
				(type default)
			)
			(layer "F.Fab")
		)
		(fp_line
			(start 0.120396 0.3048)
			(end 0.120396 0.2794)
			(stroke
				(width 0.1)
				(type default)
			)
			(layer "F.Fab")
		)
		(fp_line
			(start 0.12065 -0.3048)
			(end 0.67945 -0.3048)
			(stroke
				(width 0.1)
				(type default)
			)
			(layer "F.Fab")
		)
		(fp_line
			(start 0.12065 -0.2794)
			(end 0.12065 -0.3048)
			(stroke
				(width 0.1)
				(type default)
			)
			(layer "F.Fab")
		)
		(fp_line
			(start 0.67945 -0.3048)
			(end 0.67945 0.3048)
			(stroke
				(width 0.1)
				(type default)
			)
			(layer "F.Fab")
		)
		(fp_line
			(start 0.67945 0.3048)
			(end 0.120396 0.3048)
			(stroke
				(width 0.1)
				(type default)
			)
			(layer "F.Fab")
		)
		(pad "1" smd circle
			(at -0.40005 0)
			(size 0 0)
			(layers "F.Cu" "F.Mask" "F.Paste")
			(net "FM_SMB_RST_E1S_0_R_N")
		)
		(pad "2" smd circle
			(at 0.40005 0)
			(size 0 0)
			(layers "F.Cu" "F.Mask" "F.Paste")
			(net "RST_SMB_E1S_N")
		)
	)
	(footprint ""
		(layer "F.Cu")
		(at 90.046302 -373.03583 -90)
		(property "Reference" "C724"
			(at 0 0 270)
			(layer "F.SilkS")
			(hide yes)
			(effects
				(font
					(size 1.27 1.27)
				)
			)
		)
		(property "Value" ""
			(at 0 0 270)
			(layer "F.Fab")
			(effects
				(font
					(size 1.27 1.27)
				)
			)
		)
		(duplicate_pad_numbers_are_jumpers no)
		(fp_line
			(start -0.299974 0.150114)
			(end -0.299974 -0.150114)
			(stroke
				(width 0.1)
				(type default)
			)
			(layer "F.Fab")
		)
		(fp_line
			(start 0.299974 0.150114)
			(end -0.299974 0.150114)
			(stroke
				(width 0.1)
				(type default)
			)
			(layer "F.Fab")
		)
		(fp_line
			(start -0.299974 -0.150114)
			(end 0.299974 -0.150114)
			(stroke
				(width 0.1)
				(type default)
			)
			(layer "F.Fab")
		)
		(fp_line
			(start 0.299974 -0.150114)
			(end 0.299974 0.150114)
			(stroke
				(width 0.1)
				(type default)
			)
			(layer "F.Fab")
		)
		(pad "1" smd rect
			(at -0.2667 0 270)
			(size 0.3048 0.381)
			(layers "F.Cu" "F.Mask" "F.Paste")
			(net "P5E_CPU1_P1_TX_C_DN<8>")
		)
		(pad "2" smd rect
			(at 0.2667 0 270)
			(size 0.3048 0.381)
			(layers "F.Cu" "F.Mask" "F.Paste")
			(net "P5E_CPU1_P1_TX_DN<8>")
		)
	)
	(footprint ""
		(layer "F.Cu")
		(at 163.195 -106.807 90)
		(property "Reference" "R9028"
			(at 0 0 90)
			(layer "F.SilkS")
			(hide yes)
			(effects
				(font
					(size 1.27 1.27)
				)
			)
		)
		(property "Value" ""
			(at 0 0 90)
			(layer "F.Fab")
			(effects
				(font
					(size 1.27 1.27)
				)
			)
		)
		(duplicate_pad_numbers_are_jumpers no)
		(fp_line
			(start 0.7874 -0.4064)
			(end 0.7874 0.4064)
			(stroke
				(width 0.1524)
				(type default)
			)
			(layer "F.SilkS")
		)
		(fp_line
			(start -0.7874 -0.4064)
			(end 0.7874 -0.4064)
			(stroke
				(width 0.1524)
				(type default)
			)
			(layer "F.SilkS")
		)
		(fp_line
			(start 0.7874 0.4064)
			(end -0.7874 0.4064)
			(stroke
				(width 0.1524)
				(type default)
			)
			(layer "F.SilkS")
		)
		(fp_line
			(start -0.7874 0.4064)
			(end -0.7874 -0.4064)
			(stroke
				(width 0.1524)
				(type default)
			)
			(layer "F.SilkS")
		)
		(fp_line
			(start -0.12065 -0.305054)
			(end -0.12065 -0.2794)
			(stroke
				(width 0.1)
				(type default)
			)
			(layer "F.Fab")
		)
		(fp_line
			(start -0.67945 -0.305054)
			(end -0.12065 -0.305054)
			(stroke
				(width 0.1)
				(type default)
			)
			(layer "F.Fab")
		)
		(fp_line
			(start 0.67945 -0.3048)
			(end 0.67945 0.3048)
			(stroke
				(width 0.1)
				(type default)
			)
			(layer "F.Fab")
		)
		(fp_line
			(start 0.12065 -0.3048)
			(end 0.67945 -0.3048)
			(stroke
				(width 0.1)
				(type default)
			)
			(layer "F.Fab")
		)
		(fp_line
			(start 0.12065 -0.2794)
			(end 0.12065 -0.3048)
			(stroke
				(width 0.1)
				(type default)
			)
			(layer "F.Fab")
		)
		(fp_line
			(start -0.12065 -0.2794)
			(end 0.12065 -0.2794)
			(stroke
				(width 0.1)
				(type default)
			)
			(layer "F.Fab")
		)
		(fp_line
			(start 0.120396 0.2794)
			(end -0.12065 0.2794)
			(stroke
				(width 0.1)
				(type default)
			)
			(layer "F.Fab")
		)
		(fp_line
			(start -0.12065 0.2794)
			(end -0.12065 0.3048)
			(stroke
				(width 0.1)
				(type default)
			)
			(layer "F.Fab")
		)
		(fp_line
			(start 0.67945 0.3048)
			(end 0.120396 0.3048)
			(stroke
				(width 0.1)
				(type default)
			)
			(layer "F.Fab")
		)
		(fp_line
			(start 0.120396 0.3048)
			(end 0.120396 0.2794)
			(stroke
				(width 0.1)
				(type default)
			)
			(layer "F.Fab")
		)
		(fp_line
			(start -0.12065 0.3048)
			(end -0.67945 0.3048)
			(stroke
				(width 0.1)
				(type default)
			)
			(layer "F.Fab")
		)
		(fp_line
			(start -0.67945 0.3048)
			(end -0.67945 -0.305054)
			(stroke
				(width 0.1)
				(type default)
			)
			(layer "F.Fab")
		)
		(pad "1" smd circle
			(at -0.40005 0 90)
			(size 0 0)
			(layers "F.Cu" "F.Mask" "F.Paste")
			(net "IRQ_HSC_FAULT_N")
		)
		(pad "2" smd circle
			(at 0.40005 0 90)
			(size 0 0)
			(layers "F.Cu" "F.Mask" "F.Paste")
			(net "IRQ_HSC_FAULT_BUF_N")
		)
	)
	(footprint ""
		(layer "F.Cu")
		(at 279.513792 -121.75617)
		(property "Reference" "R2268"
			(at 0 0 0)
			(layer "F.SilkS")
			(hide yes)
			(effects
				(font
					(size 1.27 1.27)
				)
			)
		)
		(property "Value" ""
			(at 0 0 0)
			(layer "F.Fab")
			(effects
				(font
					(size 1.27 1.27)
				)
			)
		)
		(duplicate_pad_numbers_are_jumpers no)
		(fp_line
			(start -0.7874 -0.4064)
			(end 0.7874 -0.4064)
			(stroke
				(width 0.1524)
				(type default)
			)
			(layer "F.SilkS")
		)
		(fp_line
			(start -0.7874 0.4064)
			(end -0.7874 -0.4064)
			(stroke
				(width 0.1524)
				(type default)
			)
			(layer "F.SilkS")
		)
		(fp_line
			(start 0.7874 -0.4064)
			(end 0.7874 0.4064)
			(stroke
				(width 0.1524)
				(type default)
			)
			(layer "F.SilkS")
		)
		(fp_line
			(start 0.7874 0.4064)
			(end -0.7874 0.4064)
			(stroke
				(width 0.1524)
				(type default)
			)
			(layer "F.SilkS")
		)
		(fp_line
			(start -0.67945 -0.305054)
			(end -0.12065 -0.305054)
			(stroke
				(width 0.1)
				(type default)
			)
			(layer "F.Fab")
		)
		(fp_line
			(start -0.67945 0.3048)
			(end -0.67945 -0.305054)
			(stroke
				(width 0.1)
				(type default)
			)
			(layer "F.Fab")
		)
		(fp_line
			(start -0.12065 -0.305054)
			(end -0.12065 -0.2794)
			(stroke
				(width 0.1)
				(type default)
			)
			(layer "F.Fab")
		)
		(fp_line
			(start -0.12065 -0.2794)
			(end 0.12065 -0.2794)
			(stroke
				(width 0.1)
				(type default)
			)
			(layer "F.Fab")
		)
		(fp_line
			(start -0.12065 0.2794)
			(end -0.12065 0.3048)
			(stroke
				(width 0.1)
				(type default)
			)
			(layer "F.Fab")
		)
		(fp_line
			(start -0.12065 0.3048)
			(end -0.67945 0.3048)
			(stroke
				(width 0.1)
				(type default)
			)
			(layer "F.Fab")
		)
		(fp_line
			(start 0.120396 0.2794)
			(end -0.12065 0.2794)
			(stroke
				(width 0.1)
				(type default)
			)
			(layer "F.Fab")
		)
		(fp_line
			(start 0.120396 0.3048)
			(end 0.120396 0.2794)
			(stroke
				(width 0.1)
				(type default)
			)
			(layer "F.Fab")
		)
		(fp_line
			(start 0.12065 -0.3048)
			(end 0.67945 -0.3048)
			(stroke
				(width 0.1)
				(type default)
			)
			(layer "F.Fab")
		)
		(fp_line
			(start 0.12065 -0.2794)
			(end 0.12065 -0.3048)
			(stroke
				(width 0.1)
				(type default)
			)
			(layer "F.Fab")
		)
		(fp_line
			(start 0.67945 -0.3048)
			(end 0.67945 0.3048)
			(stroke
				(width 0.1)
				(type default)
			)
			(layer "F.Fab")
		)
		(fp_line
			(start 0.67945 0.3048)
			(end 0.120396 0.3048)
			(stroke
				(width 0.1)
				(type default)
			)
			(layer "F.Fab")
		)
		(pad "1" smd circle
			(at -0.40005 0)
			(size 0 0)
			(layers "F.Cu" "F.Mask" "F.Paste")
			(net "RST_SMB_SWITCH_N")
		)
		(pad "2" smd circle
			(at 0.40005 0)
			(size 0 0)
			(layers "F.Cu" "F.Mask" "F.Paste")
			(net "PU_RST_SMB_PCIE0_N")
		)
	)
	(footprint ""
		(layer "F.Cu")
		(at 334.133444 -378.95403 -90)
		(property "Reference" "C958"
			(at 0 0 270)
			(layer "F.SilkS")
			(hide yes)
			(effects
				(font
					(size 1.27 1.27)
				)
			)
		)
		(property "Value" ""
			(at 0 0 270)
			(layer "F.Fab")
			(effects
				(font
					(size 1.27 1.27)
				)
			)
		)
		(duplicate_pad_numbers_are_jumpers no)
		(fp_line
			(start -0.299974 0.150114)
			(end -0.299974 -0.150114)
			(stroke
				(width 0.1)
				(type default)
			)
			(layer "F.Fab")
		)
		(fp_line
			(start 0.299974 0.150114)
			(end -0.299974 0.150114)
			(stroke
				(width 0.1)
				(type default)
			)
			(layer "F.Fab")
		)
		(fp_line
			(start -0.299974 -0.150114)
			(end 0.299974 -0.150114)
			(stroke
				(width 0.1)
				(type default)
			)
			(layer "F.Fab")
		)
		(fp_line
			(start 0.299974 -0.150114)
			(end 0.299974 0.150114)
			(stroke
				(width 0.1)
				(type default)
			)
			(layer "F.Fab")
		)
		(pad "1" smd rect
			(at -0.2667 0 270)
			(size 0.3048 0.381)
			(layers "F.Cu" "F.Mask" "F.Paste")
			(net "P5E_CPU0_P1_TX_C_DN<3>")
		)
		(pad "2" smd rect
			(at 0.2667 0 270)
			(size 0.3048 0.381)
			(layers "F.Cu" "F.Mask" "F.Paste")
			(net "P5E_CPU0_P1_TX_DN<3>")
		)
	)
)
